(kicad_pcb
	(version 20260206)
	(generator "pcbnew")
	(generator_version "10.0")
	(general
		(thickness 1.6)
		(legacy_teardrops no)
	)
	(paper "A4")
	(title_block
		(title "03242023_DA0F0TMBIJ0_F0T_Motherboard_J_brd_V01_OCP.brd")
		(comment 1 "Grand Teton / footprints 3970-3975 of 6105")
	)
	(layers
		(0 "F.Cu" signal "TOP")
		(4 "In1.Cu" signal "GND")
		(6 "In2.Cu" signal "IN1")
		(8 "In3.Cu" signal "GND1")
		(10 "In4.Cu" signal "IN2")
		(12 "In5.Cu" signal "GND2")
		(14 "In6.Cu" signal "IN3")
		(16 "In7.Cu" signal "GND3")
		(18 "In8.Cu" signal "VCC")
		(20 "In9.Cu" signal "VCC1")
		(22 "In10.Cu" signal "GND4")
		(24 "In11.Cu" signal "IN4")
		(26 "In12.Cu" signal "GND5")
		(28 "In13.Cu" signal "IN5")
		(30 "In14.Cu" signal "GND6")
		(32 "In15.Cu" signal "IN6")
		(34 "In16.Cu" signal "GND7")
		(2 "B.Cu" signal "BOTTOM")
		(9 "F.Adhes" user "F.Adhesive")
		(11 "B.Adhes" user "B.Adhesive")
		(13 "F.Paste" user "Package Geometry/Pastemask Top")
		(15 "B.Paste" user "Package Geometry/Pastemask Bottom")
		(5 "F.SilkS" user "Ref Des/Silkscreen Top")
		(7 "B.SilkS" user "Ref Des/Silkscreen Bottom")
		(1 "F.Mask" user "Board Geometry/Soldermask Top")
		(3 "B.Mask" user "Board Geometry/Soldermask Bottom")
		(17 "Dwgs.User" user "User.Drawings")
		(19 "Cmts.User" user "User.Comments")
		(21 "Eco1.User" user "User.Eco1")
		(23 "Eco2.User" user "User.Eco2")
		(25 "Edge.Cuts" user "Board Geometry/Outline")
		(27 "Margin" user)
		(31 "F.CrtYd" user "Package Geometry/Place Bound Top")
		(29 "B.CrtYd" user "Package Geometry/Place Bound Bottom")
		(35 "F.Fab" user "Ref Des/Assembly Top")
		(33 "B.Fab" user "Ref Des/Assembly Bottom")
	)
	(footprint ""
		(layer "F.Cu")
		(at 303.821084 -426.557186 -90)
		(property "Reference" "R4125"
			(at 0 0 270)
			(layer "F.SilkS")
			(hide yes)
			(effects
				(font
					(size 1.27 1.27)
				)
			)
		)
		(property "Value" ""
			(at 0 0 270)
			(layer "F.Fab")
			(effects
				(font
					(size 1.27 1.27)
				)
			)
		)
		(duplicate_pad_numbers_are_jumpers no)
		(fp_line
			(start -0.7874 0.4064)
			(end -0.7874 -0.4064)
			(stroke
				(width 0.1524)
				(type default)
			)
			(layer "F.SilkS")
		)
		(fp_line
			(start 0.7874 0.4064)
			(end -0.7874 0.4064)
			(stroke
				(width 0.1524)
				(type default)
			)
			(layer "F.SilkS")
		)
		(fp_line
			(start -0.7874 -0.4064)
			(end 0.7874 -0.4064)
			(stroke
				(width 0.1524)
				(type default)
			)
			(layer "F.SilkS")
		)
		(fp_line
			(start 0.7874 -0.4064)
			(end 0.7874 0.4064)
			(stroke
				(width 0.1524)
				(type default)
			)
			(layer "F.SilkS")
		)
		(fp_line
			(start -0.67945 0.3048)
			(end -0.67945 -0.305054)
			(stroke
				(width 0.1)
				(type default)
			)
			(layer "F.Fab")
		)
		(fp_line
			(start -0.12065 0.3048)
			(end -0.67945 0.3048)
			(stroke
				(width 0.1)
				(type default)
			)
			(layer "F.Fab")
		)
		(fp_line
			(start 0.120396 0.3048)
			(end 0.120396 0.2794)
			(stroke
				(width 0.1)
				(type default)
			)
			(layer "F.Fab")
		)
		(fp_line
			(start 0.67945 0.3048)
			(end 0.120396 0.3048)
			(stroke
				(width 0.1)
				(type default)
			)
			(layer "F.Fab")
		)
		(fp_line
			(start -0.12065 0.2794)
			(end -0.12065 0.3048)
			(stroke
				(width 0.1)
				(type default)
			)
			(layer "F.Fab")
		)
		(fp_line
			(start 0.120396 0.2794)
			(end -0.12065 0.2794)
			(stroke
				(width 0.1)
				(type default)
			)
			(layer "F.Fab")
		)
		(fp_line
			(start -0.12065 -0.2794)
			(end 0.12065 -0.2794)
			(stroke
				(width 0.1)
				(type default)
			)
			(layer "F.Fab")
		)
		(fp_line
			(start 0.12065 -0.2794)
			(end 0.12065 -0.3048)
			(stroke
				(width 0.1)
				(type default)
			)
			(layer "F.Fab")
		)
		(fp_line
			(start 0.12065 -0.3048)
			(end 0.67945 -0.3048)
			(stroke
				(width 0.1)
				(type default)
			)
			(layer "F.Fab")
		)
		(fp_line
			(start 0.67945 -0.3048)
			(end 0.67945 0.3048)
			(stroke
				(width 0.1)
				(type default)
			)
			(layer "F.Fab")
		)
		(fp_line
			(start -0.67945 -0.305054)
			(end -0.12065 -0.305054)
			(stroke
				(width 0.1)
				(type default)
			)
			(layer "F.Fab")
		)
		(fp_line
			(start -0.12065 -0.305054)
			(end -0.12065 -0.2794)
			(stroke
				(width 0.1)
				(type default)
			)
			(layer "F.Fab")
		)
		(pad "1" smd circle
			(at -0.40005 0 270)
			(size 0 0)
			(layers "F.Cu" "F.Mask" "F.Paste")
			(net "P3V3_AUX")
		)
		(pad "2" smd circle
			(at 0.40005 0 270)
			(size 0 0)
			(layers "F.Cu" "F.Mask" "F.Paste")
			(net "GPU_3V3IO_RSVD0_FFU_N")
		)
	)
	(footprint ""
		(layer "F.Cu")
		(at 306.22367 -428.86249)
		(property "Reference" "R4578"
			(at 0 0 0)
			(layer "F.SilkS")
			(hide yes)
			(effects
				(font
					(size 1.27 1.27)
				)
			)
		)
		(property "Value" ""
			(at 0 0 0)
			(layer "F.Fab")
			(effects
				(font
					(size 1.27 1.27)
				)
			)
		)
		(duplicate_pad_numbers_are_jumpers no)
		(fp_line
			(start -0.7874 -0.4064)
			(end 0.7874 -0.4064)
			(stroke
				(width 0.1524)
				(type default)
			)
			(layer "F.SilkS")
		)
		(fp_line
			(start -0.7874 0.4064)
			(end -0.7874 -0.4064)
			(stroke
				(width 0.1524)
				(type default)
			)
			(layer "F.SilkS")
		)
		(fp_line
			(start 0.7874 -0.4064)
			(end 0.7874 0.4064)
			(stroke
				(width 0.1524)
				(type default)
			)
			(layer "F.SilkS")
		)
		(fp_line
			(start 0.7874 0.4064)
			(end -0.7874 0.4064)
			(stroke
				(width 0.1524)
				(type default)
			)
			(layer "F.SilkS")
		)
		(fp_line
			(start -0.67945 -0.305054)
			(end -0.12065 -0.305054)
			(stroke
				(width 0.1)
				(type default)
			)
			(layer "F.Fab")
		)
		(fp_line
			(start -0.67945 0.3048)
			(end -0.67945 -0.305054)
			(stroke
				(width 0.1)
				(type default)
			)
			(layer "F.Fab")
		)
		(fp_line
			(start -0.12065 -0.305054)
			(end -0.12065 -0.2794)
			(stroke
				(width 0.1)
				(type default)
			)
			(layer "F.Fab")
		)
		(fp_line
			(start -0.12065 -0.2794)
			(end 0.12065 -0.2794)
			(stroke
				(width 0.1)
				(type default)
			)
			(layer "F.Fab")
		)
		(fp_line
			(start -0.12065 0.2794)
			(end -0.12065 0.3048)
			(stroke
				(width 0.1)
				(type default)
			)
			(layer "F.Fab")
		)
		(fp_line
			(start -0.12065 0.3048)
			(end -0.67945 0.3048)
			(stroke
				(width 0.1)
				(type default)
			)
			(layer "F.Fab")
		)
		(fp_line
			(start 0.120396 0.2794)
			(end -0.12065 0.2794)
			(stroke
				(width 0.1)
				(type default)
			)
			(layer "F.Fab")
		)
		(fp_line
			(start 0.120396 0.3048)
			(end 0.120396 0.2794)
			(stroke
				(width 0.1)
				(type default)
			)
			(layer "F.Fab")
		)
		(fp_line
			(start 0.12065 -0.3048)
			(end 0.67945 -0.3048)
			(stroke
				(width 0.1)
				(type default)
			)
			(layer "F.Fab")
		)
		(fp_line
			(start 0.12065 -0.2794)
			(end 0.12065 -0.3048)
			(stroke
				(width 0.1)
				(type default)
			)
			(layer "F.Fab")
		)
		(fp_line
			(start 0.67945 -0.3048)
			(end 0.67945 0.3048)
			(stroke
				(width 0.1)
				(type default)
			)
			(layer "F.Fab")
		)
		(fp_line
			(start 0.67945 0.3048)
			(end 0.120396 0.3048)
			(stroke
				(width 0.1)
				(type default)
			)
			(layer "F.Fab")
		)
		(pad "1" smd circle
			(at -0.40005 0)
			(size 0 0)
			(layers "F.Cu" "F.Mask" "F.Paste")
			(net "PRSNT_CABLE_GPU_A2_N")
		)
		(pad "2" smd circle
			(at 0.40005 0)
			(size 0 0)
			(layers "F.Cu" "F.Mask" "F.Paste")
			(net "PRSNT_CABLE_GPU_A2_ISO_N")
		)
	)
	(footprint ""
		(layer "F.Cu")
		(at 374.46077 -402.371052 -90)
		(property "Reference" "C937"
			(at 0 0 270)
			(layer "F.SilkS")
			(hide yes)
			(effects
				(font
					(size 1.27 1.27)
				)
			)
		)
		(property "Value" ""
			(at 0 0 270)
			(layer "F.Fab")
			(effects
				(font
					(size 1.27 1.27)
				)
			)
		)
		(duplicate_pad_numbers_are_jumpers no)
		(fp_line
			(start -0.299974 0.150114)
			(end -0.299974 -0.150114)
			(stroke
				(width 0.1)
				(type default)
			)
			(layer "F.Fab")
		)
		(fp_line
			(start 0.299974 0.150114)
			(end -0.299974 0.150114)
			(stroke
				(width 0.1)
				(type default)
			)
			(layer "F.Fab")
		)
		(fp_line
			(start -0.299974 -0.150114)
			(end 0.299974 -0.150114)
			(stroke
				(width 0.1)
				(type default)
			)
			(layer "F.Fab")
		)
		(fp_line
			(start 0.299974 -0.150114)
			(end 0.299974 0.150114)
			(stroke
				(width 0.1)
				(type default)
			)
			(layer "F.Fab")
		)
		(pad "1" smd rect
			(at -0.2667 0 270)
			(size 0.3048 0.381)
			(layers "F.Cu" "F.Mask" "F.Paste")
			(net "P5E_CPU0_PE2_TX_C_DP<14>")
		)
		(pad "2" smd rect
			(at 0.2667 0 270)
			(size 0.3048 0.381)
			(layers "F.Cu" "F.Mask" "F.Paste")
			(net "P5E_CPU0_PE2_TX_DP<14>")
		)
	)
	(footprint ""
		(layer "F.Cu")
		(at 197.104 -92.801948 90)
		(property "Reference" "R4610"
			(at 0 0 90)
			(layer "F.SilkS")
			(hide yes)
			(effects
				(font
					(size 1.27 1.27)
				)
			)
		)
		(property "Value" ""
			(at 0 0 90)
			(layer "F.Fab")
			(effects
				(font
					(size 1.27 1.27)
				)
			)
		)
		(duplicate_pad_numbers_are_jumpers no)
		(fp_line
			(start 0.7874 -0.4064)
			(end 0.7874 0.4064)
			(stroke
				(width 0.1524)
				(type default)
			)
			(layer "F.SilkS")
		)
		(fp_line
			(start -0.7874 -0.4064)
			(end 0.7874 -0.4064)
			(stroke
				(width 0.1524)
				(type default)
			)
			(layer "F.SilkS")
		)
		(fp_line
			(start 0.7874 0.4064)
			(end -0.7874 0.4064)
			(stroke
				(width 0.1524)
				(type default)
			)
			(layer "F.SilkS")
		)
		(fp_line
			(start -0.7874 0.4064)
			(end -0.7874 -0.4064)
			(stroke
				(width 0.1524)
				(type default)
			)
			(layer "F.SilkS")
		)
		(fp_line
			(start -0.12065 -0.305054)
			(end -0.12065 -0.2794)
			(stroke
				(width 0.1)
				(type default)
			)
			(layer "F.Fab")
		)
		(fp_line
			(start -0.67945 -0.305054)
			(end -0.12065 -0.305054)
			(stroke
				(width 0.1)
				(type default)
			)
			(layer "F.Fab")
		)
		(fp_line
			(start 0.67945 -0.3048)
			(end 0.67945 0.3048)
			(stroke
				(width 0.1)
				(type default)
			)
			(layer "F.Fab")
		)
		(fp_line
			(start 0.12065 -0.3048)
			(end 0.67945 -0.3048)
			(stroke
				(width 0.1)
				(type default)
			)
			(layer "F.Fab")
		)
		(fp_line
			(start 0.12065 -0.2794)
			(end 0.12065 -0.3048)
			(stroke
				(width 0.1)
				(type default)
			)
			(layer "F.Fab")
		)
		(fp_line
			(start -0.12065 -0.2794)
			(end 0.12065 -0.2794)
			(stroke
				(width 0.1)
				(type default)
			)
			(layer "F.Fab")
		)
		(fp_line
			(start 0.120396 0.2794)
			(end -0.12065 0.2794)
			(stroke
				(width 0.1)
				(type default)
			)
			(layer "F.Fab")
		)
		(fp_line
			(start -0.12065 0.2794)
			(end -0.12065 0.3048)
			(stroke
				(width 0.1)
				(type default)
			)
			(layer "F.Fab")
		)
		(fp_line
			(start 0.67945 0.3048)
			(end 0.120396 0.3048)
			(stroke
				(width 0.1)
				(type default)
			)
			(layer "F.Fab")
		)
		(fp_line
			(start 0.120396 0.3048)
			(end 0.120396 0.2794)
			(stroke
				(width 0.1)
				(type default)
			)
			(layer "F.Fab")
		)
		(fp_line
			(start -0.12065 0.3048)
			(end -0.67945 0.3048)
			(stroke
				(width 0.1)
				(type default)
			)
			(layer "F.Fab")
		)
		(fp_line
			(start -0.67945 0.3048)
			(end -0.67945 -0.305054)
			(stroke
				(width 0.1)
				(type default)
			)
			(layer "F.Fab")
		)
		(pad "1" smd circle
			(at -0.40005 0 90)
			(size 0 0)
			(layers "F.Cu" "F.Mask" "F.Paste")
			(net "CLK_GEN2_GPU_FPGA_OE_R_N")
		)
		(pad "2" smd circle
			(at 0.40005 0 90)
			(size 0 0)
			(layers "F.Cu" "F.Mask" "F.Paste")
			(net "CLK_GEN2_GPU_FPGA_OE_N")
		)
	)
	(footprint ""
		(layer "F.Cu")
		(at 112.024922 -431.360072 180)
		(property "Reference" "J122"
			(at -4.893056 2.08026 0)
			(unlocked yes)
			(layer "F.SilkS")
			(effects
				(font
					(size 0.7874 0.5842)
					(thickness 0.1524)
				)
				(justify left)
			)
		)
		(property "Value" ""
			(at 0 0 180)
			(layer "F.Fab")
			(effects
				(font
					(size 1.27 1.27)
				)
			)
		)
		(duplicate_pad_numbers_are_jumpers no)
		(fp_line
			(start 3.525012 21.310092)
			(end 3.525012 7.151116)
			(stroke
				(width 0.1524)
				(type default)
			)
			(layer "F.SilkS")
		)
		(fp_line
			(start 3.525012 2.340356)
			(end 3.525012 -10.489946)
			(stroke
				(width 0.1524)
				(type default)
			)
			(layer "F.SilkS")
		)
		(fp_line
			(start 3.525012 -10.489946)
			(end -3.525012 -10.489946)
			(stroke
				(width 0.1524)
				(type default)
			)
			(layer "F.SilkS")
		)
		(fp_line
			(start -3.525012 21.310092)
			(end 3.525012 21.310092)
			(stroke
				(width 0.1524)
				(type default)
			)
			(layer "F.SilkS")
		)
		(fp_line
			(start -3.525012 10.6299)
			(end 3.525012 10.6299)
			(stroke
				(width 0.1524)
				(type default)
			)
			(layer "F.SilkS")
		)
		(fp_line
			(start -3.525012 -10.489946)
			(end -3.525012 21.310092)
			(stroke
				(width 0.1524)
				(type default)
			)
			(layer "F.SilkS")
		)
		(fp_line
			(start 3.525012 21.310092)
			(end 3.525012 -10.489946)
			(stroke
				(width 0.1)
				(type default)
			)
			(layer "F.Fab")
		)
		(fp_line
			(start 3.525012 -10.489946)
			(end -3.525012 -10.489946)
			(stroke
				(width 0.1)
				(type default)
			)
			(layer "F.Fab")
		)
		(fp_line
			(start -3.525012 21.310092)
			(end 3.525012 21.310092)
			(stroke
				(width 0.1)
				(type default)
			)
			(layer "F.Fab")
		)
		(fp_line
			(start -3.525012 -10.489946)
			(end -3.525012 21.310092)
			(stroke
				(width 0.1)
				(type default)
			)
			(layer "F.Fab")
		)
		(pad "" np_thru_hole circle
			(at 0 -6.620002 180)
			(size 3.175 3.175)
			(drill 3.175)
			(layers "*.Cu" "*.Mask")
			(clearance 0.381)
			(thermal_gap 0.381)
		)
		(pad "" np_thru_hole circle
			(at 0 0 180)
			(size 0 0)
			(drill 3.175)
			(layers "*.Cu" "*.Mask")
			(clearance 0)
		)
		(pad "" np_thru_hole circle
			(at 0 5.130038 180)
			(size 3.175 3.175)
			(drill 3.175)
			(layers "*.Cu" "*.Mask")
			(clearance 0.381)
			(thermal_gap 0.381)
		)
		(zone
			(layers "F.Cu" "B.Cu" "In1.Cu" "In2.Cu" "In3.Cu" "In4.Cu" "In5.Cu" "In6.Cu"
				"In7.Cu" "In8.Cu" "In9.Cu" "In10.Cu" "In11.Cu" "In12.Cu" "In13.Cu" "In14.Cu"
				"In15.Cu" "In16.Cu"
			)
			(hatch none 0.5)
			(connect_pads
				(clearance 0)
			)
			(min_thickness 0.25)
			(keepout
				(tracks not_allowed)
				(vias allowed)
				(pads allowed)
				(copperpour not_allowed)
				(footprints allowed)
			)
			(placement
				(enabled no)
				(sheetname "")
			)
			(fill
				(thermal_gap 0.5)
				(thermal_bridge_width 0.5)
				(island_removal_mode 0)
			)
			(polygon
				(pts
					(arc
						(start 114.120422 -436.49011)
						(mid 109.929422 -436.49011)
						(end 114.120422 -436.49011)
					)
				)
			)
		)
		(zone
			(layers "F.Cu" "B.Cu" "In1.Cu" "In2.Cu" "In3.Cu" "In4.Cu" "In5.Cu" "In6.Cu"
				"In7.Cu" "In8.Cu" "In9.Cu" "In10.Cu" "In11.Cu" "In12.Cu" "In13.Cu" "In14.Cu"
				"In15.Cu" "In16.Cu"
			)
			(hatch none 0.5)
			(connect_pads
				(clearance 0)
			)
			(min_thickness 0.25)
			(keepout
				(tracks not_allowed)
				(vias allowed)
				(pads allowed)
				(copperpour not_allowed)
				(footprints allowed)
			)
			(placement
				(enabled no)
				(sheetname "")
			)
			(fill
				(thermal_gap 0.5)
				(thermal_bridge_width 0.5)
				(island_removal_mode 0)
			)
			(polygon
				(pts
					(arc
						(start 114.120422 -424.74007)
						(mid 109.929422 -424.74007)
						(end 114.120422 -424.74007)
					)
				)
			)
		)
		(zone
			(layers "F.Cu" "B.Cu" "In1.Cu" "In2.Cu" "In3.Cu" "In4.Cu" "In5.Cu" "In6.Cu"
				"In7.Cu" "In8.Cu" "In9.Cu" "In10.Cu" "In11.Cu" "In12.Cu" "In13.Cu" "In14.Cu"
				"In15.Cu" "In16.Cu"
			)
			(hatch none 0.5)
			(connect_pads
				(clearance 0)
			)
			(min_thickness 0.25)
			(keepout
				(tracks not_allowed)
				(vias allowed)
				(pads allowed)
				(copperpour not_allowed)
				(footprints allowed)
			)
			(placement
				(enabled no)
				(sheetname "")
			)
			(fill
				(thermal_gap 0.5)
				(thermal_bridge_width 0.5)
				(island_removal_mode 0)
			)
			(polygon
				(pts
					(arc
						(start 115.644422 -431.360072)
						(mid 108.405422 -431.360072)
						(end 115.644422 -431.360072)
					)
				)
			)
		)
	)
	(footprint ""
		(layer "F.Cu")
		(at 152.32888 -47.970948 90)
		(property "Reference" "R3572"
			(at 0 0 90)
			(layer "F.SilkS")
			(hide yes)
			(effects
				(font
					(size 1.27 1.27)
				)
			)
		)
		(property "Value" ""
			(at 0 0 90)
			(layer "F.Fab")
			(effects
				(font
					(size 1.27 1.27)
				)
			)
		)
		(duplicate_pad_numbers_are_jumpers no)
		(fp_line
			(start 0.7874 -0.4064)
			(end 0.7874 0.4064)
			(stroke
				(width 0.1524)
				(type default)
			)
			(layer "F.SilkS")
		)
		(fp_line
			(start -0.7874 -0.4064)
			(end 0.7874 -0.4064)
			(stroke
				(width 0.1524)
				(type default)
			)
			(layer "F.SilkS")
		)
		(fp_line
			(start 0.7874 0.4064)
			(end -0.7874 0.4064)
			(stroke
				(width 0.1524)
				(type default)
			)
			(layer "F.SilkS")
		)
		(fp_line
			(start -0.7874 0.4064)
			(end -0.7874 -0.4064)
			(stroke
				(width 0.1524)
				(type default)
			)
			(layer "F.SilkS")
		)
		(fp_line
			(start -0.12065 -0.305054)
			(end -0.12065 -0.2794)
			(stroke
				(width 0.1)
				(type default)
			)
			(layer "F.Fab")
		)
		(fp_line
			(start -0.67945 -0.305054)
			(end -0.12065 -0.305054)
			(stroke
				(width 0.1)
				(type default)
			)
			(layer "F.Fab")
		)
		(fp_line
			(start 0.67945 -0.3048)
			(end 0.67945 0.3048)
			(stroke
				(width 0.1)
				(type default)
			)
			(layer "F.Fab")
		)
		(fp_line
			(start 0.12065 -0.3048)
			(end 0.67945 -0.3048)
			(stroke
				(width 0.1)
				(type default)
			)
			(layer "F.Fab")
		)
		(fp_line
			(start 0.12065 -0.2794)
			(end 0.12065 -0.3048)
			(stroke
				(width 0.1)
				(type default)
			)
			(layer "F.Fab")
		)
		(fp_line
			(start -0.12065 -0.2794)
			(end 0.12065 -0.2794)
			(stroke
				(width 0.1)
				(type default)
			)
			(layer "F.Fab")
		)
		(fp_line
			(start 0.120396 0.2794)
			(end -0.12065 0.2794)
			(stroke
				(width 0.1)
				(type default)
			)
			(layer "F.Fab")
		)
		(fp_line
			(start -0.12065 0.2794)
			(end -0.12065 0.3048)
			(stroke
				(width 0.1)
				(type default)
			)
			(layer "F.Fab")
		)
		(fp_line
			(start 0.67945 0.3048)
			(end 0.120396 0.3048)
			(stroke
				(width 0.1)
				(type default)
			)
			(layer "F.Fab")
		)
		(fp_line
			(start 0.120396 0.3048)
			(end 0.120396 0.2794)
			(stroke
				(width 0.1)
				(type default)
			)
			(layer "F.Fab")
		)
		(fp_line
			(start -0.12065 0.3048)
			(end -0.67945 0.3048)
			(stroke
				(width 0.1)
				(type default)
			)
			(layer "F.Fab")
		)
		(fp_line
			(start -0.67945 0.3048)
			(end -0.67945 -0.305054)
			(stroke
				(width 0.1)
				(type default)
			)
			(layer "F.Fab")
		)
		(pad "1" smd circle
			(at -0.40005 0 90)
			(size 0 0)
			(layers "F.Cu" "F.Mask" "F.Paste")
			(net "SMB_INA230_4_3V3AUX_SCL_R")
		)
		(pad "2" smd circle
			(at 0.40005 0 90)
			(size 0 0)
			(layers "F.Cu" "F.Mask" "F.Paste")
			(net "SMB_INA230_4_3V3AUX_SCL_R1")
		)
	)
)
